(kicad_pcb
	(version 20260206)
	(generator "pcbnew")
	(generator_version "10.0")
	(general
		(thickness 1.6)
		(legacy_teardrops no)
	)
	(paper "A4")
	(title_block
		(title "03242023_DA0F0TMBIJ0_F0T_Motherboard_J_brd_V01_OCP.brd")
		(comment 1 "Grand Teton / footprints 1284-1286 of 6105")
	)
	(layers
		(0 "F.Cu" signal "TOP")
		(4 "In1.Cu" signal "GND")
		(6 "In2.Cu" signal "IN1")
		(8 "In3.Cu" signal "GND1")
		(10 "In4.Cu" signal "IN2")
		(12 "In5.Cu" signal "GND2")
		(14 "In6.Cu" signal "IN3")
		(16 "In7.Cu" signal "GND3")
		(18 "In8.Cu" signal "VCC")
		(20 "In9.Cu" signal "VCC1")
		(22 "In10.Cu" signal "GND4")
		(24 "In11.Cu" signal "IN4")
		(26 "In12.Cu" signal "GND5")
		(28 "In13.Cu" signal "IN5")
		(30 "In14.Cu" signal "GND6")
		(32 "In15.Cu" signal "IN6")
		(34 "In16.Cu" signal "GND7")
		(2 "B.Cu" signal "BOTTOM")
		(9 "F.Adhes" user "F.Adhesive")
		(11 "B.Adhes" user "B.Adhesive")
		(13 "F.Paste" user "Package Geometry/Pastemask Top")
		(15 "B.Paste" user "Package Geometry/Pastemask Bottom")
		(5 "F.SilkS" user "Ref Des/Silkscreen Top")
		(7 "B.SilkS" user "Ref Des/Silkscreen Bottom")
		(1 "F.Mask" user "Board Geometry/Soldermask Top")
		(3 "B.Mask" user "Board Geometry/Soldermask Bottom")
		(17 "Dwgs.User" user "User.Drawings")
		(19 "Cmts.User" user "User.Comments")
		(21 "Eco1.User" user "User.Eco1")
		(23 "Eco2.User" user "User.Eco2")
		(25 "Edge.Cuts" user "Board Geometry/Outline")
		(27 "Margin" user)
		(31 "F.CrtYd" user "Package Geometry/Place Bound Top")
		(29 "B.CrtYd" user "Package Geometry/Place Bound Bottom")
		(35 "F.Fab" user "Ref Des/Assembly Top")
		(33 "B.Fab" user "Ref Des/Assembly Bottom")
	)
	(footprint ""
		(layer "F.Cu")
		(at 14.265402 -105.537762 90)
		(property "Reference" "R4419"
			(at 0 0 90)
			(layer "F.SilkS")
			(hide yes)
			(effects
				(font
					(size 1.27 1.27)
				)
			)
		)
		(property "Value" ""
			(at 0 0 90)
			(layer "F.Fab")
			(effects
				(font
					(size 1.27 1.27)
				)
			)
		)
		(duplicate_pad_numbers_are_jumpers no)
		(fp_line
			(start 0.7874 -0.4064)
			(end 0.7874 0.4064)
			(stroke
				(width 0.1524)
				(type default)
			)
			(layer "F.SilkS")
		)
		(fp_line
			(start -0.7874 -0.4064)
			(end 0.7874 -0.4064)
			(stroke
				(width 0.1524)
				(type default)
			)
			(layer "F.SilkS")
		)
		(fp_line
			(start 0.7874 0.4064)
			(end 0.004318 0.4064)
			(stroke
				(width 0.1524)
				(type default)
			)
			(layer "F.SilkS")
		)
		(fp_line
			(start -0.7874 0.4064)
			(end -0.7874 -0.4064)
			(stroke
				(width 0.1524)
				(type default)
			)
			(layer "F.SilkS")
		)
		(fp_line
			(start -0.12065 -0.305054)
			(end -0.12065 -0.2794)
			(stroke
				(width 0.1)
				(type default)
			)
			(layer "F.Fab")
		)
		(fp_line
			(start -0.67945 -0.305054)
			(end -0.12065 -0.305054)
			(stroke
				(width 0.1)
				(type default)
			)
			(layer "F.Fab")
		)
		(fp_line
			(start 0.67945 -0.3048)
			(end 0.67945 0.3048)
			(stroke
				(width 0.1)
				(type default)
			)
			(layer "F.Fab")
		)
		(fp_line
			(start 0.12065 -0.3048)
			(end 0.67945 -0.3048)
			(stroke
				(width 0.1)
				(type default)
			)
			(layer "F.Fab")
		)
		(fp_line
			(start 0.12065 -0.2794)
			(end 0.12065 -0.3048)
			(stroke
				(width 0.1)
				(type default)
			)
			(layer "F.Fab")
		)
		(fp_line
			(start -0.12065 -0.2794)
			(end 0.12065 -0.2794)
			(stroke
				(width 0.1)
				(type default)
			)
			(layer "F.Fab")
		)
		(fp_line
			(start 0.120396 0.2794)
			(end -0.12065 0.2794)
			(stroke
				(width 0.1)
				(type default)
			)
			(layer "F.Fab")
		)
		(fp_line
			(start -0.12065 0.2794)
			(end -0.12065 0.3048)
			(stroke
				(width 0.1)
				(type default)
			)
			(layer "F.Fab")
		)
		(fp_line
			(start 0.67945 0.3048)
			(end 0.120396 0.3048)
			(stroke
				(width 0.1)
				(type default)
			)
			(layer "F.Fab")
		)
		(fp_line
			(start 0.120396 0.3048)
			(end 0.120396 0.2794)
			(stroke
				(width 0.1)
				(type default)
			)
			(layer "F.Fab")
		)
		(fp_line
			(start -0.12065 0.3048)
			(end -0.67945 0.3048)
			(stroke
				(width 0.1)
				(type default)
			)
			(layer "F.Fab")
		)
		(fp_line
			(start -0.67945 0.3048)
			(end -0.67945 -0.305054)
			(stroke
				(width 0.1)
				(type default)
			)
			(layer "F.Fab")
		)
		(pad "1" smd circle
			(at -0.40005 0 90)
			(size 0 0)
			(layers "F.Cu" "F.Mask" "F.Paste")
			(net "USB2_HOST_BMC_B_DP")
		)
		(pad "2" smd circle
			(at 0.40005 0 90)
			(size 0 0)
			(layers "F.Cu" "F.Mask" "F.Paste")
			(net "GND")
		)
	)
	(footprint ""
		(layer "F.Cu")
		(at 126.01448 -96.258126 -90)
		(property "Reference" "Q139"
			(at -4.103624 0.79248 0)
			(unlocked yes)
			(layer "F.SilkS")
			(effects
				(font
					(size 0.635 0.4064)
					(thickness 0.1524)
				)
			)
		)
		(property "Value" ""
			(at 0 0 270)
			(layer "F.Fab")
			(effects
				(font
					(size 1.27 1.27)
				)
			)
		)
		(duplicate_pad_numbers_are_jumpers no)
		(fp_line
			(start -1.376172 1.199896)
			(end -1.376172 -1.199896)
			(stroke
				(width 0.1524)
				(type default)
			)
			(layer "F.SilkS")
		)
		(fp_line
			(start 1.376172 1.199896)
			(end -1.376172 1.199896)
			(stroke
				(width 0.1524)
				(type default)
			)
			(layer "F.SilkS")
		)
		(fp_line
			(start 0 -0.762)
			(end 0.508 -1.199896)
			(stroke
				(width 0.1524)
				(type default)
			)
			(layer "F.SilkS")
		)
		(fp_line
			(start -1.376172 -1.199896)
			(end -0.508 -1.199896)
			(stroke
				(width 0.1524)
				(type default)
			)
			(layer "F.SilkS")
		)
		(fp_line
			(start -0.508 -1.199896)
			(end 0 -0.762)
			(stroke
				(width 0.1524)
				(type default)
			)
			(layer "F.SilkS")
		)
		(fp_line
			(start 0.508 -1.199896)
			(end 1.376172 -1.199896)
			(stroke
				(width 0.1524)
				(type default)
			)
			(layer "F.SilkS")
		)
		(fp_line
			(start 1.376172 -1.199896)
			(end 1.376172 1.199896)
			(stroke
				(width 0.1524)
				(type default)
			)
			(layer "F.SilkS")
		)
		(fp_poly
			(pts
				(xy -1.5875 -0.7493) (xy -2.3495 -1.1303) (xy -2.3495 -0.3683)
			)
			(stroke
				(width 0)
				(type default)
			)
			(fill yes)
			(layer "F.SilkS")
		)
		(fp_line
			(start -0.674878 1.100074)
			(end -0.674878 -1.100074)
			(stroke
				(width 0.1)
				(type default)
			)
			(layer "F.Fab")
		)
		(fp_line
			(start 0.674878 1.100074)
			(end -0.674878 1.100074)
			(stroke
				(width 0.1)
				(type default)
			)
			(layer "F.Fab")
		)
		(fp_line
			(start -0.674878 -1.100074)
			(end 0.674878 -1.100074)
			(stroke
				(width 0.1)
				(type default)
			)
			(layer "F.Fab")
		)
		(fp_line
			(start 0.674878 -1.100074)
			(end 0.674878 1.100074)
			(stroke
				(width 0.1)
				(type default)
			)
			(layer "F.Fab")
		)
		(fp_poly
			(pts
				(xy -1.4605 -0.7493) (xy -2.2225 -1.1303) (xy -2.2225 -0.3683)
			)
			(stroke
				(width 0)
				(type default)
			)
			(fill yes)
			(layer "F.Fab")
		)
		(pad "1" smd rect
			(at -0.899922 -0.750062 180)
			(size 0.6096 0.6096)
			(layers "F.Cu" "F.Mask" "F.Paste")
			(net "GND")
		)
		(pad "2" smd rect
			(at -0.899922 0 180)
			(size 0.4064 0.6096)
			(layers "F.Cu" "F.Mask" "F.Paste")
			(net "H_CPU1_THERMTRIP_R_N")
		)
		(pad "3" smd rect
			(at -0.899922 0.750062 180)
			(size 0.6096 0.6096)
			(layers "F.Cu" "F.Mask" "F.Paste")
			(net "H_CPU1_THERMTRIP_N")
		)
		(pad "4" smd rect
			(at 0.899922 0.750062 180)
			(size 0.6096 0.6096)
			(layers "F.Cu" "F.Mask" "F.Paste")
			(net "PVNN_TERM_CPU1")
		)
		(pad "5" smd rect
			(at 0.899922 0 180)
			(size 0.4064 0.6096)
			(layers "F.Cu" "F.Mask" "F.Paste")
			(net "H_CPU1_THERMTRIP_VT_R_N")
		)
		(pad "6" smd rect
			(at 0.899922 -0.750062 180)
			(size 0.6096 0.6096)
			(layers "F.Cu" "F.Mask" "F.Paste")
			(net "H_CPU1_THERMTRIP_VT_N")
		)
	)
	(footprint ""
		(layer "F.Cu")
		(at 416.097974 -167.25265 180)
		(property "Reference" "PC189_P0_1"
			(at 0 0 180)
			(layer "F.SilkS")
			(hide yes)
			(effects
				(font
					(size 1.27 1.27)
				)
			)
		)
		(property "Value" ""
			(at 0 0 180)
			(layer "F.Fab")
			(effects
				(font
					(size 1.27 1.27)
				)
			)
		)
		(duplicate_pad_numbers_are_jumpers no)
		(fp_line
			(start 0.7874 0.4064)
			(end -0.7874 0.4064)
			(stroke
				(width 0.1524)
				(type default)
			)
			(layer "F.SilkS")
		)
		(fp_line
			(start 0.7874 -0.4064)
			(end 0.7874 0.4064)
			(stroke
				(width 0.1524)
				(type default)
			)
			(layer "F.SilkS")
		)
		(fp_line
			(start -0.7874 0.4064)
			(end -0.7874 -0.4064)
			(stroke
				(width 0.1524)
				(type default)
			)
			(layer "F.SilkS")
		)
		(fp_line
			(start -0.7874 -0.4064)
			(end 0.7874 -0.4064)
			(stroke
				(width 0.1524)
				(type default)
			)
			(layer "F.SilkS")
		)
		(fp_line
			(start 0.67945 0.3048)
			(end 0.120396 0.3048)
			(stroke
				(width 0.1)
				(type default)
			)
			(layer "F.Fab")
		)
		(fp_line
			(start 0.67945 -0.3048)
			(end 0.67945 0.3048)
			(stroke
				(width 0.1)
				(type default)
			)
			(layer "F.Fab")
		)
		(fp_line
			(start 0.12065 -0.2794)
			(end 0.12065 -0.3048)
			(stroke
				(width 0.1)
				(type default)
			)
			(layer "F.Fab")
		)
		(fp_line
			(start 0.12065 -0.3048)
			(end 0.67945 -0.3048)
			(stroke
				(width 0.1)
				(type default)
			)
			(layer "F.Fab")
		)
		(fp_line
			(start 0.120396 0.3048)
			(end 0.120396 0.2794)
			(stroke
				(width 0.1)
				(type default)
			)
			(layer "F.Fab")
		)
		(fp_line
			(start 0.120396 0.2794)
			(end -0.12065 0.2794)
			(stroke
				(width 0.1)
				(type default)
			)
			(layer "F.Fab")
		)
		(fp_line
			(start -0.12065 0.3048)
			(end -0.67945 0.3048)
			(stroke
				(width 0.1)
				(type default)
			)
			(layer "F.Fab")
		)
		(fp_line
			(start -0.12065 0.2794)
			(end -0.12065 0.3048)
			(stroke
				(width 0.1)
				(type default)
			)
			(layer "F.Fab")
		)
		(fp_line
			(start -0.12065 -0.2794)
			(end 0.12065 -0.2794)
			(stroke
				(width 0.1)
				(type default)
			)
			(layer "F.Fab")
		)
		(fp_line
			(start -0.12065 -0.305054)
			(end -0.12065 -0.2794)
			(stroke
				(width 0.1)
				(type default)
			)
			(layer "F.Fab")
		)
		(fp_line
			(start -0.67945 0.3048)
			(end -0.67945 -0.305054)
			(stroke
				(width 0.1)
				(type default)
			)
			(layer "F.Fab")
		)
		(fp_line
			(start -0.67945 -0.305054)
			(end -0.12065 -0.305054)
			(stroke
				(width 0.1)
				(type default)
			)
			(layer "F.Fab")
		)
		(pad "1" smd circle
			(at -0.40005 0 180)
			(size 0 0)
			(layers "F.Cu" "F.Mask" "F.Paste")
			(net "SW_P12V_PVCCINFAON_CPU0_FLT")
		)
		(pad "2" smd circle
			(at 0.40005 0 180)
			(size 0 0)
			(layers "F.Cu" "F.Mask" "F.Paste")
			(net "GND")
		)
	)
)
